(kicad_pcb
	(version 20260206)
	(generator "pcbnew")
	(generator_version "10.0")
	(general
		(thickness 1.6)
		(legacy_teardrops no)
	)
	(paper "A4")
	(title_block
		(title "timecard-production-celestica-r4006 — R4006-B0001-02_R01.brd")
		(comment 1 "Time Appliance Project (Time Card) / footprints 1075-1079 of 1113")
	)
	(layers
		(0 "F.Cu" signal "TOP")
		(4 "In1.Cu" signal "L02_GND1")
		(6 "In2.Cu" signal "L03_SIG1")
		(8 "In3.Cu" signal "L04_GND2")
		(10 "In4.Cu" signal "L05_VCC1")
		(12 "In5.Cu" signal "L06_VCC2")
		(14 "In6.Cu" signal "L07_GND3")
		(16 "In7.Cu" signal "L08_SIG2")
		(18 "In8.Cu" signal "L09_GND4")
		(2 "B.Cu" signal "BOTTOM")
		(9 "F.Adhes" user "F.Adhesive")
		(11 "B.Adhes" user "B.Adhesive")
		(13 "F.Paste" user "Package Geometry/Pastemask Top")
		(15 "B.Paste" user "Package Geometry/Pastemask Bottom")
		(5 "F.SilkS" user "Ref Des/Silkscreen Top")
		(7 "B.SilkS" user "Ref Des/Silkscreen Bottom")
		(1 "F.Mask" user "Board Geometry/Soldermask Top")
		(3 "B.Mask" user "Board Geometry/Soldermask Bottom")
		(17 "Dwgs.User" user "User.Drawings")
		(19 "Cmts.User" user "User.Comments")
		(21 "Eco1.User" user "User.Eco1")
		(23 "Eco2.User" user "User.Eco2")
		(25 "Edge.Cuts" user "Board Geometry/Outline")
		(27 "Margin" user)
		(31 "F.CrtYd" user "Package Geometry/Place Bound Top")
		(29 "B.CrtYd" user "Package Geometry/Place Bound Bottom")
		(35 "F.Fab" user "Ref Des/Assembly Top")
		(33 "B.Fab" user "Ref Des/Assembly Bottom")
	)
	(footprint ""
		(layer "B.Cu")
		(at 146.685 -19.685 90)
		(property "Reference" "R225"
			(at 2.794 -0.03937 270)
			(unlocked yes)
			(layer "B.SilkS")
			(effects
				(font
					(size 0.7874 0.5842)
					(thickness 0.1524)
				)
				(justify mirror)
			)
		)
		(property "Value" "VAL*"
			(at -0.02032 2.13233 90)
			(unlocked yes)
			(layer "B.Fab")
			(hide yes)
			(effects
				(font
					(size 0.7874 0.5842)
					(thickness 0.1524)
				)
				(justify mirror)
			)
		)
		(property "Tolerance" "TOL*"
			(at -0.044704 3.05435 90)
			(unlocked yes)
			(layer "Cmts.User")
			(hide yes)
			(effects
				(font
					(size 0.7874 0.5842)
					(thickness 0.1524)
				)
				(justify mirror)
			)
		)
		(property "User Part Number" "PARTNUM*"
			(at -0.02032 4.024884 90)
			(unlocked yes)
			(layer "Cmts.User")
			(hide yes)
			(effects
				(font
					(size 0.7874 0.5842)
					(thickness 0.1524)
				)
				(justify mirror)
			)
		)
		(property "Device Type" "RESISTOR-G155-13300-01,330OHM,A"
			(at -0.008382 1.210564 90)
			(unlocked yes)
			(layer "B.Fab")
			(hide yes)
			(effects
				(font
					(size 0.7874 0.5842)
					(thickness 0.1524)
				)
				(justify mirror)
			)
		)
		(duplicate_pad_numbers_are_jumpers no)
		(fp_line
			(start 1.143 -0.5588)
			(end 1.143 0.5588)
			(stroke
				(width 0.1)
				(type default)
			)
			(layer "B.SilkS")
		)
		(fp_line
			(start -1.143 -0.5588)
			(end 1.143 -0.5588)
			(stroke
				(width 0.1)
				(type default)
			)
			(layer "B.SilkS")
		)
		(fp_line
			(start 1.143 0.5588)
			(end -1.143 0.5588)
			(stroke
				(width 0.1)
				(type default)
			)
			(layer "B.SilkS")
		)
		(fp_line
			(start -1.143 0.5588)
			(end -1.143 -0.5588)
			(stroke
				(width 0.1)
				(type default)
			)
			(layer "B.SilkS")
		)
		(fp_rect
			(start 1.143 -0.5588)
			(end -1.143 0.5588)
			(stroke
				(width 0)
				(type default)
			)
			(fill no)
			(layer "B.CrtYd")
		)
		(fp_line
			(start 0.508 -0.3048)
			(end 0.508 0.3048)
			(stroke
				(width 0.1)
				(type default)
			)
			(layer "B.Fab")
		)
		(fp_line
			(start -0.508 -0.3048)
			(end 0.508 -0.3048)
			(stroke
				(width 0.1)
				(type default)
			)
			(layer "B.Fab")
		)
		(fp_line
			(start 0.508 0.3048)
			(end -0.508 0.3048)
			(stroke
				(width 0.1)
				(type default)
			)
			(layer "B.Fab")
		)
		(fp_line
			(start -0.508 0.3048)
			(end -0.508 -0.3048)
			(stroke
				(width 0.1)
				(type default)
			)
			(layer "B.Fab")
		)
		(pad "1" smd rect
			(at 0.5334 0 270)
			(size 0.7112 0.6096)
			(layers "B.Cu" "B.Mask" "B.Paste")
			(net "XP1R8V_FPGA_PG")
		)
		(pad "2" smd rect
			(at -0.5334 0 270)
			(size 0.7112 0.6096)
			(layers "B.Cu" "B.Mask" "B.Paste")
			(net "UNNAMED_515_CAPACITOR_I128_1")
		)
		(zone
			(layer "B.Cu")
			(hatch none 0.5)
			(connect_pads
				(clearance 0)
			)
			(min_thickness 0.25)
			(keepout
				(tracks allowed)
				(vias not_allowed)
				(pads allowed)
				(copperpour not_allowed)
				(footprints allowed)
			)
			(placement
				(enabled no)
				(sheetname "")
			)
			(fill
				(thermal_gap 0.5)
				(thermal_bridge_width 0.5)
				(island_removal_mode 0)
			)
			(polygon
				(pts
					(xy 146.3802 -19.7612) (xy 146.3802 -19.6088) (xy 146.9898 -19.6088) (xy 146.9898 -19.7612)
				)
			)
		)
	)
	(footprint ""
		(layer "B.Cu")
		(at 115.443 -72.263 180)
		(property "Reference" "C229"
			(at 0.127 -2.45237 0)
			(unlocked yes)
			(layer "B.SilkS")
			(effects
				(font
					(size 0.7874 0.5842)
					(thickness 0.1524)
				)
				(justify mirror)
			)
		)
		(property "Value" "VAL*"
			(at -0.0762 2.067306 180)
			(unlocked yes)
			(layer "B.Fab")
			(hide yes)
			(effects
				(font
					(size 0.7874 0.5842)
					(thickness 0.1524)
				)
				(justify mirror)
			)
		)
		(property "Tolerance" "TOL*"
			(at -0.0762 3.032506 180)
			(unlocked yes)
			(layer "Cmts.User")
			(hide yes)
			(effects
				(font
					(size 0.7874 0.5842)
					(thickness 0.1524)
				)
				(justify mirror)
			)
		)
		(property "User Part Number" "PARTNUM*"
			(at -0.1016 4.023106 180)
			(unlocked yes)
			(layer "Cmts.User")
			(hide yes)
			(effects
				(font
					(size 0.7874 0.5842)
					(thickness 0.1524)
				)
				(justify mirror)
			)
		)
		(property "Device Type" "CAPACITOR-G105-0B104-CK,0.1UF,A"
			(at -0.0508 1.127506 180)
			(unlocked yes)
			(layer "B.Fab")
			(hide yes)
			(effects
				(font
					(size 0.7874 0.5842)
					(thickness 0.1524)
				)
				(justify mirror)
			)
		)
		(duplicate_pad_numbers_are_jumpers no)
		(fp_line
			(start 1.143 0.5588)
			(end -1.143 0.5588)
			(stroke
				(width 0.1)
				(type default)
			)
			(layer "B.SilkS")
		)
		(fp_line
			(start 1.143 -0.5588)
			(end 1.143 0.5588)
			(stroke
				(width 0.1)
				(type default)
			)
			(layer "B.SilkS")
		)
		(fp_line
			(start -1.143 0.5588)
			(end -1.143 -0.5588)
			(stroke
				(width 0.1)
				(type default)
			)
			(layer "B.SilkS")
		)
		(fp_line
			(start -1.143 -0.5588)
			(end 1.143 -0.5588)
			(stroke
				(width 0.1)
				(type default)
			)
			(layer "B.SilkS")
		)
		(fp_rect
			(start 1.143 0.5588)
			(end -1.143 -0.5588)
			(stroke
				(width 0)
				(type default)
			)
			(fill no)
			(layer "B.CrtYd")
		)
		(fp_line
			(start 0.508 0.3048)
			(end -0.508 0.3048)
			(stroke
				(width 0.1)
				(type default)
			)
			(layer "B.Fab")
		)
		(fp_line
			(start 0.508 -0.3048)
			(end 0.508 0.3048)
			(stroke
				(width 0.1)
				(type default)
			)
			(layer "B.Fab")
		)
		(fp_line
			(start -0.508 0.3048)
			(end -0.508 -0.3048)
			(stroke
				(width 0.1)
				(type default)
			)
			(layer "B.Fab")
		)
		(fp_line
			(start -0.508 -0.3048)
			(end 0.508 -0.3048)
			(stroke
				(width 0.1)
				(type default)
			)
			(layer "B.Fab")
		)
		(pad "1" smd rect
			(at 0.5334 0)
			(size 0.7112 0.6096)
			(layers "B.Cu" "B.Mask" "B.Paste")
			(net "XP3R3V_FPGA_EN_R")
		)
		(pad "2" smd rect
			(at -0.5334 0)
			(size 0.7112 0.6096)
			(layers "B.Cu" "B.Mask" "B.Paste")
			(net "SG")
		)
		(zone
			(layer "B.Cu")
			(hatch none 0.5)
			(connect_pads
				(clearance 0)
			)
			(min_thickness 0.25)
			(keepout
				(tracks allowed)
				(vias not_allowed)
				(pads allowed)
				(copperpour not_allowed)
				(footprints allowed)
			)
			(placement
				(enabled no)
				(sheetname "")
			)
			(fill
				(thermal_gap 0.5)
				(thermal_bridge_width 0.5)
				(island_removal_mode 0)
			)
			(polygon
				(pts
					(xy 115.3668 -72.5678) (xy 115.3668 -71.9582) (xy 115.5192 -71.9582) (xy 115.5192 -72.5678)
				)
			)
		)
	)
	(footprint ""
		(layer "B.Cu")
		(at 101.847142 -41.323006 90)
		(property "Reference" "C131"
			(at -0.937006 -42.061892 270)
			(unlocked yes)
			(layer "B.SilkS")
			(effects
				(font
					(size 0.635 0.4064)
					(thickness 0.1524)
				)
				(justify mirror)
			)
		)
		(property "Value" "VAL*"
			(at 0 3.718306 90)
			(unlocked yes)
			(layer "B.Fab")
			(hide yes)
			(effects
				(font
					(size 0.7874 0.5842)
					(thickness 0.127)
				)
				(justify mirror)
			)
		)
		(property "Tolerance" "TOL*"
			(at 0 4.861306 90)
			(unlocked yes)
			(layer "Cmts.User")
			(hide yes)
			(effects
				(font
					(size 0.7874 0.5842)
					(thickness 0.127)
				)
				(justify mirror)
			)
		)
		(property "User Part Number" "PARTNUM*"
			(at 0 2.575306 90)
			(unlocked yes)
			(layer "Cmts.User")
			(hide yes)
			(effects
				(font
					(size 0.7874 0.5842)
					(thickness 0.127)
				)
				(justify mirror)
			)
		)
		(property "Device Type" "CAPACITOR-G105-0F475-BM,4.7UF,A"
			(at 0 1.432306 90)
			(unlocked yes)
			(layer "B.Fab")
			(hide yes)
			(effects
				(font
					(size 0.7874 0.5842)
					(thickness 0.127)
				)
				(justify mirror)
			)
		)
		(duplicate_pad_numbers_are_jumpers no)
		(fp_line
			(start 0.970026 -0.4699)
			(end -0.970026 -0.4699)
			(stroke
				(width 0.1)
				(type default)
			)
			(layer "B.SilkS")
		)
		(fp_line
			(start -0.970026 -0.4699)
			(end -0.970026 0.4699)
			(stroke
				(width 0.1)
				(type default)
			)
			(layer "B.SilkS")
		)
		(fp_line
			(start 0.970026 0.4699)
			(end 0.970026 -0.4699)
			(stroke
				(width 0.1)
				(type default)
			)
			(layer "B.SilkS")
		)
		(fp_line
			(start -0.970026 0.4699)
			(end 0.970026 0.4699)
			(stroke
				(width 0.1)
				(type default)
			)
			(layer "B.SilkS")
		)
		(fp_poly
			(pts
				(xy 0.970026 0.4699) (xy -0.970026 0.4699) (xy -0.970026 -0.4699) (xy 0.970026 -0.4699)
			)
			(stroke
				(width 0)
				(type default)
			)
			(fill no)
			(layer "B.CrtYd")
		)
		(fp_line
			(start 0.508 -0.3048)
			(end -0.508 -0.3048)
			(stroke
				(width 0.1)
				(type default)
			)
			(layer "B.Fab")
		)
		(fp_line
			(start -0.508 -0.3048)
			(end -0.508 0.3048)
			(stroke
				(width 0.1)
				(type default)
			)
			(layer "B.Fab")
		)
		(fp_line
			(start 0.508 0.3048)
			(end 0.508 -0.3048)
			(stroke
				(width 0.1)
				(type default)
			)
			(layer "B.Fab")
		)
		(fp_line
			(start -0.508 0.3048)
			(end 0.508 0.3048)
			(stroke
				(width 0.1)
				(type default)
			)
			(layer "B.Fab")
		)
		(pad "1" smd circle
			(at 0.500126 0 270)
			(size 0.635 0.635)
			(layers "B.Cu" "B.Mask" "B.Paste")
			(net "XP1R0V_FPGA_MGTAVCC")
		)
		(pad "2" smd circle
			(at -0.500126 0 270)
			(size 0.635 0.635)
			(layers "B.Cu" "B.Mask" "B.Paste")
			(net "SG")
		)
	)
	(footprint ""
		(layer "B.Cu")
		(at 139.6492 -87.4014)
		(property "Reference" "C301"
			(at 0.3048 -5.01523 0)
			(unlocked yes)
			(layer "B.SilkS")
			(effects
				(font
					(size 0.7874 0.5842)
					(thickness 0.1524)
				)
				(justify mirror)
			)
		)
		(property "Value" "VAL*"
			(at -0.0762 3.134106 0)
			(unlocked yes)
			(layer "B.Fab")
			(hide yes)
			(effects
				(font
					(size 0.7874 0.5842)
					(thickness 0.1524)
				)
				(justify mirror)
			)
		)
		(property "Tolerance" "TOL*"
			(at -0.0762 4.048506 0)
			(unlocked yes)
			(layer "Cmts.User")
			(hide yes)
			(effects
				(font
					(size 0.7874 0.5842)
					(thickness 0.1524)
				)
				(justify mirror)
			)
		)
		(property "User Part Number" "PARTNUM*"
			(at -0.1016 5.013706 0)
			(unlocked yes)
			(layer "Cmts.User")
			(hide yes)
			(effects
				(font
					(size 0.7874 0.5842)
					(thickness 0.1524)
				)
				(justify mirror)
			)
		)
		(property "Device Type" "CAPACITOR-G107-0F106-EM,10UF,2A"
			(at -0.0508 2.194306 0)
			(unlocked yes)
			(layer "B.Fab")
			(hide yes)
			(effects
				(font
					(size 0.7874 0.5842)
					(thickness 0.1524)
				)
				(justify mirror)
			)
		)
		(duplicate_pad_numbers_are_jumpers no)
		(fp_line
			(start -1.5748 -0.9398)
			(end 1.5748 -0.9398)
			(stroke
				(width 0.1)
				(type default)
			)
			(layer "B.SilkS")
		)
		(fp_line
			(start -1.5748 0.9398)
			(end -1.5748 -0.9398)
			(stroke
				(width 0.1)
				(type default)
			)
			(layer "B.SilkS")
		)
		(fp_line
			(start 1.5748 -0.9398)
			(end 1.5748 0.9398)
			(stroke
				(width 0.1)
				(type default)
			)
			(layer "B.SilkS")
		)
		(fp_line
			(start 1.5748 0.9398)
			(end -1.5748 0.9398)
			(stroke
				(width 0.1)
				(type default)
			)
			(layer "B.SilkS")
		)
		(fp_rect
			(start 1.5748 0.9398)
			(end -1.5748 -0.9398)
			(stroke
				(width 0)
				(type default)
			)
			(fill no)
			(layer "B.CrtYd")
		)
		(fp_line
			(start -1.016 -0.635)
			(end 1.016 -0.635)
			(stroke
				(width 0.1)
				(type default)
			)
			(layer "B.Fab")
		)
		(fp_line
			(start -1.016 0.635)
			(end -1.016 -0.635)
			(stroke
				(width 0.1)
				(type default)
			)
			(layer "B.Fab")
		)
		(fp_line
			(start 1.016 -0.635)
			(end 1.016 0.635)
			(stroke
				(width 0.1)
				(type default)
			)
			(layer "B.Fab")
		)
		(fp_line
			(start 1.016 0.635)
			(end -1.016 0.635)
			(stroke
				(width 0.1)
				(type default)
			)
			(layer "B.Fab")
		)
		(pad "1" smd rect
			(at 0.8382 0 180)
			(size 0.9652 1.3716)
			(layers "B.Cu" "B.Mask" "B.Paste")
			(net "XP12R0V_IN")
		)
		(pad "2" smd rect
			(at -0.8382 0 180)
			(size 0.9652 1.3716)
			(layers "B.Cu" "B.Mask" "B.Paste")
			(net "SG")
		)
		(zone
			(layer "B.Cu")
			(hatch none 0.5)
			(connect_pads
				(clearance 0)
			)
			(min_thickness 0.25)
			(keepout
				(tracks not_allowed)
				(vias allowed)
				(pads allowed)
				(copperpour not_allowed)
				(footprints allowed)
			)
			(placement
				(enabled no)
				(sheetname "")
			)
			(fill
				(thermal_gap 0.5)
				(thermal_bridge_width 0.5)
				(island_removal_mode 0)
			)
			(polygon
				(pts
					(xy 139.8778 -86.7664) (xy 139.8778 -88.0364) (xy 139.4206 -88.0364) (xy 139.4206 -86.7664)
				)
			)
		)
		(zone
			(layer "B.Cu")
			(hatch none 0.5)
			(connect_pads
				(clearance 0)
			)
			(min_thickness 0.25)
			(keepout
				(tracks allowed)
				(vias not_allowed)
				(pads allowed)
				(copperpour not_allowed)
				(footprints allowed)
			)
			(placement
				(enabled no)
				(sheetname "")
			)
			(fill
				(thermal_gap 0.5)
				(thermal_bridge_width 0.5)
				(island_removal_mode 0)
			)
			(polygon
				(pts
					(xy 139.8778 -86.7664) (xy 139.8778 -88.0364) (xy 139.4206 -88.0364) (xy 139.4206 -86.7664)
				)
			)
		)
	)
	(footprint ""
		(layer "B.Cu")
		(at 108.458 -20.447 90)
		(property "Reference" "L14"
			(at 0.635 1.48463 270)
			(unlocked yes)
			(layer "B.SilkS")
			(effects
				(font
					(size 0.7874 0.5842)
					(thickness 0.1524)
				)
				(justify mirror)
			)
		)
		(property "Value" "VAL*"
			(at -0.014732 2.526538 90)
			(unlocked yes)
			(layer "B.Fab")
			(hide yes)
			(effects
				(font
					(size 0.7874 0.5842)
					(thickness 0.000001)
				)
				(justify mirror)
			)
		)
		(property "Tolerance" "TOL*"
			(at -0.014732 3.503676 90)
			(unlocked yes)
			(layer "Cmts.User")
			(hide yes)
			(effects
				(font
					(size 0.7874 0.5842)
					(thickness 0.000001)
				)
				(justify mirror)
			)
		)
		(property "User Part Number" "PARTNUM*"
			(at -0.02794 4.480814 90)
			(unlocked yes)
			(layer "Cmts.User")
			(hide yes)
			(effects
				(font
					(size 0.7874 0.5842)
					(thickness 0.000001)
				)
				(justify mirror)
			)
		)
		(property "Device Type" "FERRITEBEAD-G191-10097-01,600OA"
			(at -0.014732 1.600708 90)
			(unlocked yes)
			(layer "B.Fab")
			(hide yes)
			(effects
				(font
					(size 0.7874 0.5842)
					(thickness 0.000001)
				)
				(justify mirror)
			)
		)
		(duplicate_pad_numbers_are_jumpers no)
		(fp_line
			(start 1.3208 -0.7112)
			(end -1.3208 -0.7112)
			(stroke
				(width 0.1)
				(type default)
			)
			(layer "B.SilkS")
		)
		(fp_line
			(start -1.3208 -0.7112)
			(end -1.3208 0.7112)
			(stroke
				(width 0.1)
				(type default)
			)
			(layer "B.SilkS")
		)
		(fp_line
			(start 1.3208 0.7112)
			(end 1.3208 -0.7112)
			(stroke
				(width 0.1)
				(type default)
			)
			(layer "B.SilkS")
		)
		(fp_line
			(start -1.3208 0.7112)
			(end 1.3208 0.7112)
			(stroke
				(width 0.1)
				(type default)
			)
			(layer "B.SilkS")
		)
		(fp_rect
			(start 1.3208 0.7112)
			(end -1.3208 -0.7112)
			(stroke
				(width 0)
				(type default)
			)
			(fill no)
			(layer "B.CrtYd")
		)
		(fp_line
			(start 0.8128 -0.4572)
			(end -0.8128 -0.4572)
			(stroke
				(width 0.1)
				(type default)
			)
			(layer "B.Fab")
		)
		(fp_line
			(start -0.8128 -0.4572)
			(end -0.8128 0.4572)
			(stroke
				(width 0.1)
				(type default)
			)
			(layer "B.Fab")
		)
		(fp_line
			(start 0.8128 0.4572)
			(end 0.8128 -0.4572)
			(stroke
				(width 0.1)
				(type default)
			)
			(layer "B.Fab")
		)
		(fp_line
			(start -0.8128 0.4572)
			(end 0.8128 0.4572)
			(stroke
				(width 0.1)
				(type default)
			)
			(layer "B.Fab")
		)
		(pad "1" smd rect
			(at 0.6858 0 270)
			(size 0.762 0.8636)
			(layers "B.Cu" "B.Mask" "B.Paste")
			(net "VDD3V3_OSC_200M")
		)
		(pad "2" smd rect
			(at -0.6858 0 270)
			(size 0.762 0.8636)
			(layers "B.Cu" "B.Mask" "B.Paste")
			(net "XP3R3V")
		)
		(zone
			(layer "B.Cu")
			(hatch none 0.5)
			(connect_pads
				(clearance 0)
			)
			(min_thickness 0.25)
			(keepout
				(tracks allowed)
				(vias not_allowed)
				(pads allowed)
				(copperpour not_allowed)
				(footprints allowed)
			)
			(placement
				(enabled no)
				(sheetname "")
			)
			(fill
				(thermal_gap 0.5)
				(thermal_bridge_width 0.5)
				(island_removal_mode 0)
			)
			(polygon
				(pts
					(xy 108.9152 -20.5994) (xy 108.0008 -20.5994) (xy 108.0008 -20.2946) (xy 108.9152 -20.2946)
				)
			)
		)
		(zone
			(layer "B.Cu")
			(hatch none 0.5)
			(connect_pads
				(clearance 0)
			)
			(min_thickness 0.25)
			(keepout
				(tracks not_allowed)
				(vias allowed)
				(pads allowed)
				(copperpour not_allowed)
				(footprints allowed)
			)
			(placement
				(enabled no)
				(sheetname "")
			)
			(fill
				(thermal_gap 0.5)
				(thermal_bridge_width 0.5)
				(island_removal_mode 0)
			)
			(polygon
				(pts
					(xy 108.9152 -20.5994) (xy 108.0008 -20.5994) (xy 108.0008 -20.2946) (xy 108.9152 -20.2946)
				)
			)
		)
	)
)
